FILE_TYPE = CONNECTIVITY;
{Allegro Design Entry HDL 17.2-2016 S081 (4005846) 1/11/2022}
"PAGE_NUMBER" = 2;
0"NC";
END.
